(kicad_pcb
	(version 20260206)
	(generator "pcbnew")
	(generator_version "10.0")
	(general
		(thickness 1.6)
		(legacy_teardrops no)
	)
	(paper "A4")
	(title_block
		(title "03242023_DA0F0TMBIJ0_F0T_Motherboard_J_brd_V01_OCP.brd")
		(comment 1 "Grand Teton / footprints 2019-2025 of 6105")
	)
	(layers
		(0 "F.Cu" signal "TOP")
		(4 "In1.Cu" signal "GND")
		(6 "In2.Cu" signal "IN1")
		(8 "In3.Cu" signal "GND1")
		(10 "In4.Cu" signal "IN2")
		(12 "In5.Cu" signal "GND2")
		(14 "In6.Cu" signal "IN3")
		(16 "In7.Cu" signal "GND3")
		(18 "In8.Cu" signal "VCC")
		(20 "In9.Cu" signal "VCC1")
		(22 "In10.Cu" signal "GND4")
		(24 "In11.Cu" signal "IN4")
		(26 "In12.Cu" signal "GND5")
		(28 "In13.Cu" signal "IN5")
		(30 "In14.Cu" signal "GND6")
		(32 "In15.Cu" signal "IN6")
		(34 "In16.Cu" signal "GND7")
		(2 "B.Cu" signal "BOTTOM")
		(9 "F.Adhes" user "F.Adhesive")
		(11 "B.Adhes" user "B.Adhesive")
		(13 "F.Paste" user "Package Geometry/Pastemask Top")
		(15 "B.Paste" user "Package Geometry/Pastemask Bottom")
		(5 "F.SilkS" user "Ref Des/Silkscreen Top")
		(7 "B.SilkS" user "Ref Des/Silkscreen Bottom")
		(1 "F.Mask" user "Board Geometry/Soldermask Top")
		(3 "B.Mask" user "Board Geometry/Soldermask Bottom")
		(17 "Dwgs.User" user "User.Drawings")
		(19 "Cmts.User" user "User.Comments")
		(21 "Eco1.User" user "User.Eco1")
		(23 "Eco2.User" user "User.Eco2")
		(25 "Edge.Cuts" user "Board Geometry/Outline")
		(27 "Margin" user)
		(31 "F.CrtYd" user "Package Geometry/Place Bound Top")
		(29 "B.CrtYd" user "Package Geometry/Place Bound Bottom")
		(35 "F.Fab" user "Ref Des/Assembly Top")
		(33 "B.Fab" user "Ref Des/Assembly Bottom")
	)
	(footprint ""
		(layer "F.Cu")
		(at 179.352448 -404.287482 180)
		(property "Reference" "PR3935"
			(at 0 0 180)
			(layer "F.SilkS")
			(hide yes)
			(effects
				(font
					(size 1.27 1.27)
				)
			)
		)
		(property "Value" ""
			(at 0 0 180)
			(layer "F.Fab")
			(effects
				(font
					(size 1.27 1.27)
				)
			)
		)
		(duplicate_pad_numbers_are_jumpers no)
		(fp_line
			(start 0.7874 0.4064)
			(end -0.7874 0.4064)
			(stroke
				(width 0.1524)
				(type default)
			)
			(layer "F.SilkS")
		)
		(fp_line
			(start 0.7874 -0.4064)
			(end 0.7874 0.4064)
			(stroke
				(width 0.1524)
				(type default)
			)
			(layer "F.SilkS")
		)
		(fp_line
			(start -0.7874 0.4064)
			(end -0.7874 -0.4064)
			(stroke
				(width 0.1524)
				(type default)
			)
			(layer "F.SilkS")
		)
		(fp_line
			(start -0.7874 -0.4064)
			(end 0.7874 -0.4064)
			(stroke
				(width 0.1524)
				(type default)
			)
			(layer "F.SilkS")
		)
		(fp_line
			(start 0.67945 0.3048)
			(end 0.120396 0.3048)
			(stroke
				(width 0.1)
				(type default)
			)
			(layer "F.Fab")
		)
		(fp_line
			(start 0.67945 -0.3048)
			(end 0.67945 0.3048)
			(stroke
				(width 0.1)
				(type default)
			)
			(layer "F.Fab")
		)
		(fp_line
			(start 0.12065 -0.2794)
			(end 0.12065 -0.3048)
			(stroke
				(width 0.1)
				(type default)
			)
			(layer "F.Fab")
		)
		(fp_line
			(start 0.12065 -0.3048)
			(end 0.67945 -0.3048)
			(stroke
				(width 0.1)
				(type default)
			)
			(layer "F.Fab")
		)
		(fp_line
			(start 0.120396 0.3048)
			(end 0.120396 0.2794)
			(stroke
				(width 0.1)
				(type default)
			)
			(layer "F.Fab")
		)
		(fp_line
			(start 0.120396 0.2794)
			(end -0.12065 0.2794)
			(stroke
				(width 0.1)
				(type default)
			)
			(layer "F.Fab")
		)
		(fp_line
			(start -0.12065 0.3048)
			(end -0.67945 0.3048)
			(stroke
				(width 0.1)
				(type default)
			)
			(layer "F.Fab")
		)
		(fp_line
			(start -0.12065 0.2794)
			(end -0.12065 0.3048)
			(stroke
				(width 0.1)
				(type default)
			)
			(layer "F.Fab")
		)
		(fp_line
			(start -0.12065 -0.2794)
			(end 0.12065 -0.2794)
			(stroke
				(width 0.1)
				(type default)
			)
			(layer "F.Fab")
		)
		(fp_line
			(start -0.12065 -0.305054)
			(end -0.12065 -0.2794)
			(stroke
				(width 0.1)
				(type default)
			)
			(layer "F.Fab")
		)
		(fp_line
			(start -0.67945 0.3048)
			(end -0.67945 -0.305054)
			(stroke
				(width 0.1)
				(type default)
			)
			(layer "F.Fab")
		)
		(fp_line
			(start -0.67945 -0.305054)
			(end -0.12065 -0.305054)
			(stroke
				(width 0.1)
				(type default)
			)
			(layer "F.Fab")
		)
		(pad "1" smd circle
			(at -0.40005 0 180)
			(size 0 0)
			(layers "F.Cu" "F.Mask" "F.Paste")
			(net "HSC_VTEMP")
		)
		(pad "2" smd circle
			(at 0.40005 0 180)
			(size 0 0)
			(layers "F.Cu" "F.Mask" "F.Paste")
			(net "AGND_HSC")
		)
	)
	(footprint ""
		(layer "F.Cu")
		(at 333.784448 -408.517344 -90)
		(property "Reference" "C921"
			(at 0 0 270)
			(layer "F.SilkS")
			(hide yes)
			(effects
				(font
					(size 1.27 1.27)
				)
			)
		)
		(property "Value" ""
			(at 0 0 270)
			(layer "F.Fab")
			(effects
				(font
					(size 1.27 1.27)
				)
			)
		)
		(duplicate_pad_numbers_are_jumpers no)
		(fp_line
			(start -0.299974 0.150114)
			(end -0.299974 -0.150114)
			(stroke
				(width 0.1)
				(type default)
			)
			(layer "F.Fab")
		)
		(fp_line
			(start 0.299974 0.150114)
			(end -0.299974 0.150114)
			(stroke
				(width 0.1)
				(type default)
			)
			(layer "F.Fab")
		)
		(fp_line
			(start -0.299974 -0.150114)
			(end 0.299974 -0.150114)
			(stroke
				(width 0.1)
				(type default)
			)
			(layer "F.Fab")
		)
		(fp_line
			(start 0.299974 -0.150114)
			(end 0.299974 0.150114)
			(stroke
				(width 0.1)
				(type default)
			)
			(layer "F.Fab")
		)
		(pad "1" smd rect
			(at -0.2667 0 270)
			(size 0.3048 0.381)
			(layers "F.Cu" "F.Mask" "F.Paste")
			(net "P5E_CPU0_PE0_TX_C_DP<6>")
		)
		(pad "2" smd rect
			(at 0.2667 0 270)
			(size 0.3048 0.381)
			(layers "F.Cu" "F.Mask" "F.Paste")
			(net "P5E_CPU0_PE0_TX_DP<6>")
		)
	)
	(footprint ""
		(layer "F.Cu")
		(at 153.022554 -408.517344 -90)
		(property "Reference" "C1537"
			(at 0 0 270)
			(layer "F.SilkS")
			(hide yes)
			(effects
				(font
					(size 1.27 1.27)
				)
			)
		)
		(property "Value" ""
			(at 0 0 270)
			(layer "F.Fab")
			(effects
				(font
					(size 1.27 1.27)
				)
			)
		)
		(duplicate_pad_numbers_are_jumpers no)
		(fp_line
			(start -0.299974 0.150114)
			(end -0.299974 -0.150114)
			(stroke
				(width 0.1)
				(type default)
			)
			(layer "F.Fab")
		)
		(fp_line
			(start 0.299974 0.150114)
			(end -0.299974 0.150114)
			(stroke
				(width 0.1)
				(type default)
			)
			(layer "F.Fab")
		)
		(fp_line
			(start -0.299974 -0.150114)
			(end 0.299974 -0.150114)
			(stroke
				(width 0.1)
				(type default)
			)
			(layer "F.Fab")
		)
		(fp_line
			(start 0.299974 -0.150114)
			(end 0.299974 0.150114)
			(stroke
				(width 0.1)
				(type default)
			)
			(layer "F.Fab")
		)
		(pad "1" smd rect
			(at -0.2667 0 270)
			(size 0.3048 0.381)
			(layers "F.Cu" "F.Mask" "F.Paste")
			(net "P5E_CPU1_PE3_TX_C_DP<5>")
		)
		(pad "2" smd rect
			(at 0.2667 0 270)
			(size 0.3048 0.381)
			(layers "F.Cu" "F.Mask" "F.Paste")
			(net "P5E_CPU1_PE3_TX_DP<5>")
		)
	)
	(footprint ""
		(layer "F.Cu")
		(at 24.069802 -406.874218)
		(property "Reference" "R3498"
			(at 0 0 0)
			(layer "F.SilkS")
			(hide yes)
			(effects
				(font
					(size 1.27 1.27)
				)
			)
		)
		(property "Value" ""
			(at 0 0 0)
			(layer "F.Fab")
			(effects
				(font
					(size 1.27 1.27)
				)
			)
		)
		(duplicate_pad_numbers_are_jumpers no)
		(fp_line
			(start -0.7874 -0.4064)
			(end 0.7874 -0.4064)
			(stroke
				(width 0.1524)
				(type default)
			)
			(layer "F.SilkS")
		)
		(fp_line
			(start -0.7874 0.4064)
			(end -0.7874 -0.4064)
			(stroke
				(width 0.1524)
				(type default)
			)
			(layer "F.SilkS")
		)
		(fp_line
			(start 0.7874 -0.4064)
			(end 0.7874 0.4064)
			(stroke
				(width 0.1524)
				(type default)
			)
			(layer "F.SilkS")
		)
		(fp_line
			(start 0.7874 0.4064)
			(end -0.7874 0.4064)
			(stroke
				(width 0.1524)
				(type default)
			)
			(layer "F.SilkS")
		)
		(fp_line
			(start -0.67945 -0.305054)
			(end -0.12065 -0.305054)
			(stroke
				(width 0.1)
				(type default)
			)
			(layer "F.Fab")
		)
		(fp_line
			(start -0.67945 0.3048)
			(end -0.67945 -0.305054)
			(stroke
				(width 0.1)
				(type default)
			)
			(layer "F.Fab")
		)
		(fp_line
			(start -0.12065 -0.305054)
			(end -0.12065 -0.2794)
			(stroke
				(width 0.1)
				(type default)
			)
			(layer "F.Fab")
		)
		(fp_line
			(start -0.12065 -0.2794)
			(end 0.12065 -0.2794)
			(stroke
				(width 0.1)
				(type default)
			)
			(layer "F.Fab")
		)
		(fp_line
			(start -0.12065 0.2794)
			(end -0.12065 0.3048)
			(stroke
				(width 0.1)
				(type default)
			)
			(layer "F.Fab")
		)
		(fp_line
			(start -0.12065 0.3048)
			(end -0.67945 0.3048)
			(stroke
				(width 0.1)
				(type default)
			)
			(layer "F.Fab")
		)
		(fp_line
			(start 0.120396 0.2794)
			(end -0.12065 0.2794)
			(stroke
				(width 0.1)
				(type default)
			)
			(layer "F.Fab")
		)
		(fp_line
			(start 0.120396 0.3048)
			(end 0.120396 0.2794)
			(stroke
				(width 0.1)
				(type default)
			)
			(layer "F.Fab")
		)
		(fp_line
			(start 0.12065 -0.3048)
			(end 0.67945 -0.3048)
			(stroke
				(width 0.1)
				(type default)
			)
			(layer "F.Fab")
		)
		(fp_line
			(start 0.12065 -0.2794)
			(end 0.12065 -0.3048)
			(stroke
				(width 0.1)
				(type default)
			)
			(layer "F.Fab")
		)
		(fp_line
			(start 0.67945 -0.3048)
			(end 0.67945 0.3048)
			(stroke
				(width 0.1)
				(type default)
			)
			(layer "F.Fab")
		)
		(fp_line
			(start 0.67945 0.3048)
			(end 0.120396 0.3048)
			(stroke
				(width 0.1)
				(type default)
			)
			(layer "F.Fab")
		)
		(pad "1" smd circle
			(at -0.40005 0)
			(size 0 0)
			(layers "F.Cu" "F.Mask" "F.Paste")
			(net "P3V3_AUX")
		)
		(pad "2" smd circle
			(at 0.40005 0)
			(size 0 0)
			(layers "F.Cu" "F.Mask" "F.Paste")
			(net "GPU_FPGA_THERM_OVERT_N")
		)
	)
	(footprint ""
		(layer "F.Cu")
		(at 301.45482 -419.02761 -90)
		(property "Reference" "C2265"
			(at 0 0 270)
			(layer "F.SilkS")
			(hide yes)
			(effects
				(font
					(size 1.27 1.27)
				)
			)
		)
		(property "Value" ""
			(at 0 0 270)
			(layer "F.Fab")
			(effects
				(font
					(size 1.27 1.27)
				)
			)
		)
		(duplicate_pad_numbers_are_jumpers no)
		(fp_line
			(start -0.7874 0.4064)
			(end -0.7874 -0.4064)
			(stroke
				(width 0.1524)
				(type default)
			)
			(layer "F.SilkS")
		)
		(fp_line
			(start 0.7874 0.4064)
			(end -0.7874 0.4064)
			(stroke
				(width 0.1524)
				(type default)
			)
			(layer "F.SilkS")
		)
		(fp_line
			(start -0.7874 -0.4064)
			(end 0.7874 -0.4064)
			(stroke
				(width 0.1524)
				(type default)
			)
			(layer "F.SilkS")
		)
		(fp_line
			(start 0.7874 -0.4064)
			(end 0.7874 0.4064)
			(stroke
				(width 0.1524)
				(type default)
			)
			(layer "F.SilkS")
		)
		(fp_line
			(start -0.67945 0.3048)
			(end -0.67945 -0.305054)
			(stroke
				(width 0.1)
				(type default)
			)
			(layer "F.Fab")
		)
		(fp_line
			(start -0.12065 0.3048)
			(end -0.67945 0.3048)
			(stroke
				(width 0.1)
				(type default)
			)
			(layer "F.Fab")
		)
		(fp_line
			(start 0.120396 0.3048)
			(end 0.120396 0.2794)
			(stroke
				(width 0.1)
				(type default)
			)
			(layer "F.Fab")
		)
		(fp_line
			(start 0.67945 0.3048)
			(end 0.120396 0.3048)
			(stroke
				(width 0.1)
				(type default)
			)
			(layer "F.Fab")
		)
		(fp_line
			(start -0.12065 0.2794)
			(end -0.12065 0.3048)
			(stroke
				(width 0.1)
				(type default)
			)
			(layer "F.Fab")
		)
		(fp_line
			(start 0.120396 0.2794)
			(end -0.12065 0.2794)
			(stroke
				(width 0.1)
				(type default)
			)
			(layer "F.Fab")
		)
		(fp_line
			(start -0.12065 -0.2794)
			(end 0.12065 -0.2794)
			(stroke
				(width 0.1)
				(type default)
			)
			(layer "F.Fab")
		)
		(fp_line
			(start 0.12065 -0.2794)
			(end 0.12065 -0.3048)
			(stroke
				(width 0.1)
				(type default)
			)
			(layer "F.Fab")
		)
		(fp_line
			(start 0.12065 -0.3048)
			(end 0.67945 -0.3048)
			(stroke
				(width 0.1)
				(type default)
			)
			(layer "F.Fab")
		)
		(fp_line
			(start 0.67945 -0.3048)
			(end 0.67945 0.3048)
			(stroke
				(width 0.1)
				(type default)
			)
			(layer "F.Fab")
		)
		(fp_line
			(start -0.67945 -0.305054)
			(end -0.12065 -0.305054)
			(stroke
				(width 0.1)
				(type default)
			)
			(layer "F.Fab")
		)
		(fp_line
			(start -0.12065 -0.305054)
			(end -0.12065 -0.2794)
			(stroke
				(width 0.1)
				(type default)
			)
			(layer "F.Fab")
		)
		(pad "1" smd circle
			(at -0.40005 0 270)
			(size 0 0)
			(layers "F.Cu" "F.Mask" "F.Paste")
			(net "PRSNT_CABLE_GPU_B3_ISO_N")
		)
		(pad "2" smd circle
			(at 0.40005 0 270)
			(size 0 0)
			(layers "F.Cu" "F.Mask" "F.Paste")
			(net "GND")
		)
	)
	(footprint ""
		(layer "F.Cu")
		(at 304.53965 -61.130688 180)
		(property "Reference" "R2252"
			(at 0 0 180)
			(layer "F.SilkS")
			(hide yes)
			(effects
				(font
					(size 1.27 1.27)
				)
			)
		)
		(property "Value" ""
			(at 0 0 180)
			(layer "F.Fab")
			(effects
				(font
					(size 1.27 1.27)
				)
			)
		)
		(duplicate_pad_numbers_are_jumpers no)
		(fp_line
			(start 0.7874 0.4064)
			(end -0.7874 0.4064)
			(stroke
				(width 0.1524)
				(type default)
			)
			(layer "F.SilkS")
		)
		(fp_line
			(start 0.7874 -0.4064)
			(end 0.7874 0.4064)
			(stroke
				(width 0.1524)
				(type default)
			)
			(layer "F.SilkS")
		)
		(fp_line
			(start -0.7874 0.4064)
			(end -0.7874 -0.4064)
			(stroke
				(width 0.1524)
				(type default)
			)
			(layer "F.SilkS")
		)
		(fp_line
			(start -0.7874 -0.4064)
			(end 0.7874 -0.4064)
			(stroke
				(width 0.1524)
				(type default)
			)
			(layer "F.SilkS")
		)
		(fp_line
			(start 0.67945 0.3048)
			(end 0.120396 0.3048)
			(stroke
				(width 0.1)
				(type default)
			)
			(layer "F.Fab")
		)
		(fp_line
			(start 0.67945 -0.3048)
			(end 0.67945 0.3048)
			(stroke
				(width 0.1)
				(type default)
			)
			(layer "F.Fab")
		)
		(fp_line
			(start 0.12065 -0.2794)
			(end 0.12065 -0.3048)
			(stroke
				(width 0.1)
				(type default)
			)
			(layer "F.Fab")
		)
		(fp_line
			(start 0.12065 -0.3048)
			(end 0.67945 -0.3048)
			(stroke
				(width 0.1)
				(type default)
			)
			(layer "F.Fab")
		)
		(fp_line
			(start 0.120396 0.3048)
			(end 0.120396 0.2794)
			(stroke
				(width 0.1)
				(type default)
			)
			(layer "F.Fab")
		)
		(fp_line
			(start 0.120396 0.2794)
			(end -0.12065 0.2794)
			(stroke
				(width 0.1)
				(type default)
			)
			(layer "F.Fab")
		)
		(fp_line
			(start -0.12065 0.3048)
			(end -0.67945 0.3048)
			(stroke
				(width 0.1)
				(type default)
			)
			(layer "F.Fab")
		)
		(fp_line
			(start -0.12065 0.2794)
			(end -0.12065 0.3048)
			(stroke
				(width 0.1)
				(type default)
			)
			(layer "F.Fab")
		)
		(fp_line
			(start -0.12065 -0.2794)
			(end 0.12065 -0.2794)
			(stroke
				(width 0.1)
				(type default)
			)
			(layer "F.Fab")
		)
		(fp_line
			(start -0.12065 -0.305054)
			(end -0.12065 -0.2794)
			(stroke
				(width 0.1)
				(type default)
			)
			(layer "F.Fab")
		)
		(fp_line
			(start -0.67945 0.3048)
			(end -0.67945 -0.305054)
			(stroke
				(width 0.1)
				(type default)
			)
			(layer "F.Fab")
		)
		(fp_line
			(start -0.67945 -0.305054)
			(end -0.12065 -0.305054)
			(stroke
				(width 0.1)
				(type default)
			)
			(layer "F.Fab")
		)
		(pad "1" smd circle
			(at -0.40005 0 180)
			(size 0 0)
			(layers "F.Cu" "F.Mask" "F.Paste")
			(net "PECI_MUX_SEL_R")
		)
		(pad "2" smd circle
			(at 0.40005 0 180)
			(size 0 0)
			(layers "F.Cu" "F.Mask" "F.Paste")
			(net "GND")
		)
	)
	(footprint ""
		(layer "F.Cu")
		(at 31.29788 -432.907948)
		(property "Reference" "R3468"
			(at 0 0 0)
			(layer "F.SilkS")
			(hide yes)
			(effects
				(font
					(size 1.27 1.27)
				)
			)
		)
		(property "Value" ""
			(at 0 0 0)
			(layer "F.Fab")
			(effects
				(font
					(size 1.27 1.27)
				)
			)
		)
		(duplicate_pad_numbers_are_jumpers no)
		(fp_line
			(start -0.7874 -0.4064)
			(end 0.7874 -0.4064)
			(stroke
				(width 0.1524)
				(type default)
			)
			(layer "F.SilkS")
		)
		(fp_line
			(start -0.7874 0.4064)
			(end -0.7874 -0.4064)
			(stroke
				(width 0.1524)
				(type default)
			)
			(layer "F.SilkS")
		)
		(fp_line
			(start 0.7874 -0.4064)
			(end 0.7874 0.4064)
			(stroke
				(width 0.1524)
				(type default)
			)
			(layer "F.SilkS")
		)
		(fp_line
			(start 0.7874 0.4064)
			(end -0.7874 0.4064)
			(stroke
				(width 0.1524)
				(type default)
			)
			(layer "F.SilkS")
		)
		(fp_line
			(start -0.67945 -0.305054)
			(end -0.12065 -0.305054)
			(stroke
				(width 0.1)
				(type default)
			)
			(layer "F.Fab")
		)
		(fp_line
			(start -0.67945 0.3048)
			(end -0.67945 -0.305054)
			(stroke
				(width 0.1)
				(type default)
			)
			(layer "F.Fab")
		)
		(fp_line
			(start -0.12065 -0.305054)
			(end -0.12065 -0.2794)
			(stroke
				(width 0.1)
				(type default)
			)
			(layer "F.Fab")
		)
		(fp_line
			(start -0.12065 -0.2794)
			(end 0.12065 -0.2794)
			(stroke
				(width 0.1)
				(type default)
			)
			(layer "F.Fab")
		)
		(fp_line
			(start -0.12065 0.2794)
			(end -0.12065 0.3048)
			(stroke
				(width 0.1)
				(type default)
			)
			(layer "F.Fab")
		)
		(fp_line
			(start -0.12065 0.3048)
			(end -0.67945 0.3048)
			(stroke
				(width 0.1)
				(type default)
			)
			(layer "F.Fab")
		)
		(fp_line
			(start 0.120396 0.2794)
			(end -0.12065 0.2794)
			(stroke
				(width 0.1)
				(type default)
			)
			(layer "F.Fab")
		)
		(fp_line
			(start 0.120396 0.3048)
			(end 0.120396 0.2794)
			(stroke
				(width 0.1)
				(type default)
			)
			(layer "F.Fab")
		)
		(fp_line
			(start 0.12065 -0.3048)
			(end 0.67945 -0.3048)
			(stroke
				(width 0.1)
				(type default)
			)
			(layer "F.Fab")
		)
		(fp_line
			(start 0.12065 -0.2794)
			(end 0.12065 -0.3048)
			(stroke
				(width 0.1)
				(type default)
			)
			(layer "F.Fab")
		)
		(fp_line
			(start 0.67945 -0.3048)
			(end 0.67945 0.3048)
			(stroke
				(width 0.1)
				(type default)
			)
			(layer "F.Fab")
		)
		(fp_line
			(start 0.67945 0.3048)
			(end 0.120396 0.3048)
			(stroke
				(width 0.1)
				(type default)
			)
			(layer "F.Fab")
		)
		(pad "1" smd circle
			(at -0.40005 0)
			(size 0 0)
			(layers "F.Cu" "F.Mask" "F.Paste")
			(net "RST_PERST_2_SWB_BUF_R_N")
		)
		(pad "2" smd circle
			(at 0.40005 0)
			(size 0 0)
			(layers "F.Cu" "F.Mask" "F.Paste")
			(net "RST_PERST_2_SWB_BUF_N")
		)
	)
)
